#ISCELL
  mstr_misc dns *
  *
#ISCELL
  pure_quanta quanta_title_block_c *
  *
#ISCELL
  pure_quanta_power universal_power *
  page379_i1
#ISCELL
  standard offpage *
  page379_i10
#ISCELL
  standard offpage *
  page379_i11
#ISCELL
  standard offpage *
  page379_i12
#ISCELL
  standard offpage *
  page379_i13
#ISCELL
  standard offpage *
  page379_i14
#CELL
  pure_quanta q_res *
  page379_i15
#ISCELL
  pure_quanta_power universal_gnd *
  page379_i16
#CELL
  pure_quanta q_res *
  page379_i17
#ISCELL
  pure_quanta_power universal_power *
  page379_i18
#CELL
  pure_quanta q_inductor *
  page379_i2
#CELL
  pure_quanta q_res *
  page379_i20
#CELL
  pure_quanta q_res *
  page379_i21
#ISCELL
  pure_quanta_power universal_gnd *
  page379_i23
#CELL
  pure_quanta q_cap *
  page379_i24
#ISCELL
  pure_quanta_power universal_gnd *
  page379_i25
#CELL
  pure_quanta q_cap *
  page379_i26
#ISCELL
  pure_quanta_power universal_power *
  page379_i27
#ISCELL
  pure_quanta_power universal_power *
  page379_i28
#ISCELL
  pure_quanta_power universal_power *
  page379_i29
#ISCELL
  pure_quanta_power universal_gnd *
  page379_i3
#ISCELL
  pure_quanta_power universal_power *
  page379_i30
#ISCELL
  pure_quanta_power universal_power *
  page379_i31
#CELL
  pure_quanta q_inductor *
  page379_i32
#CELL
  pure_quanta q_cap *
  page379_i34
#CELL
  pure_quanta q_cap *
  page379_i35
#CELL
  pure_quanta q_cap *
  page379_i36
#ISCELL
  standard offpage *
  page379_i37
#ISCELL
  pure_quanta_power universal_gnd *
  page379_i38
#CELL
  pure_quanta q_res *
  page379_i49
#CELL
  pure_quanta q_res *
  page379_i50
#CELL
  pure_quanta q_res *
  page379_i51
#ISCELL
  pure_quanta_power universal_power *
  page379_i56
#ISCELL
  standard offpage *
  page379_i57
#CELL
  pure_quanta q_cap *
  page379_i58
#ISCELL
  pure_quanta_power universal_gnd *
  page379_i59
#CELL
  pure_quanta q_cap *
  page379_i60
#ISCELL
  pure_quanta_power universal_power *
  page379_i61
#CELL
  pure_quanta 9zxl0451ekilft *
  page379_i63
#CELL
  pure_quanta q_res *
  page379_i64
#CELL
  pure_quanta q_res *
  page379_i65
#ISCELL
  standard offpage *
  page379_i66
#ISCELL
  standard offpage *
  page379_i67
#ISCELL
  standard offpage *
  page379_i68
#ISCELL
  standard offpage *
  page379_i69
#ISCELL
  pure_quanta_power universal_power *
  page379_i7
#ISCELL
  standard offpage *
  page379_i70
#ISCELL
  standard offpage *
  page379_i71
#ISCELL
  standard offpage *
  page379_i72
#ISCELL
  standard offpage *
  page379_i73
#CELL
  pure_quanta q_res *
  page379_i76
#CELL
  pure_quanta q_cap *
  page379_i77
#CELL
  pure_quanta q_cap *
  page379_i78
#CELL
  pure_quanta q_cap *
  page379_i79
#ISCELL
  pure_quanta_power universal_gnd *
  page379_i80
#CELL
  pure_quanta q_res *
  page379_i81
#ISCELL
  pure_quanta_power universal_power *
  page379_i82
#ISCELL
  standard offpage *
  page379_i9
